(kicad_pcb
	(version 20241229)
	(generator "pcbnew")
	(generator_version "9.0")
	(general
		(thickness 1.599998)
		(legacy_teardrops no)
	)
	(paper "A4")
	(title_block
		(date "2023-02-12")
		(rev "1.1.5")
		(comment 9 "footprint 108 of 473 (U3), pads 230-311 of 484")
	)
	(layers
		(0 "F.Cu" signal)
		(4 "In1.Cu" power "In1.GND")
		(6 "In2.Cu" signal)
		(8 "In3.Cu" power "In3.GND")
		(10 "In4.Cu" power "In4.VCC")
		(12 "In5.Cu" signal)
		(14 "In6.Cu" power "In6.VCC")
		(2 "B.Cu" signal)
		(9 "F.Adhes" user "F.Adhesive")
		(11 "B.Adhes" user "B.Adhesive")
		(13 "F.Paste" user)
		(15 "B.Paste" user)
		(5 "F.SilkS" user "F.Silkscreen")
		(7 "B.SilkS" user "B.Silkscreen")
		(1 "F.Mask" user)
		(3 "B.Mask" user)
		(17 "Dwgs.User" user "User.Drawings")
		(19 "Cmts.User" user "User.Comments")
		(21 "Eco1.User" user "User.Eco1")
		(23 "Eco2.User" user "User.Eco2")
		(25 "Edge.Cuts" user)
		(27 "Margin" user)
		(31 "F.CrtYd" user "F.Courtyard")
		(29 "B.CrtYd" user "B.Courtyard")
		(35 "F.Fab" user)
		(33 "B.Fab" user)
	)
	(footprint "antmicro-footprints:BGA-484_23x23mm_Layout22x22_P1mm_FBG484"
		(locked yes)
		(layer "F.Cu")
		(at 169.036328 95.997157 -90)
		(property "Reference" "U3"
			(at -11.8 -12 270)
			(layer "F.SilkS")
			(effects
				(font
					(size 0.7 0.7)
					(thickness 0.15)
				)
				(justify left bottom)
			)
		)
		(property "Value" "XC7K70T-FBG484"
			(at -10.4 0.4 270)
			(layer "F.Fab")
			(effects
				(font
					(size 0.7 0.7)
					(thickness 0.15)
				)
				(justify left bottom)
			)
		)
		(property "Description" "Kintex®-7 Field Programmable Gate Array (FPGA) IC 285 484-BBGA, FCBGA"
			(at 0 0 270)
			(layer "F.Fab")
			(hide yes)
			(effects
				(font
					(size 1.27 1.27)
					(thickness 0.15)
				)
			)
		)
		(property "Author" "Antmicro"
			(at 73.039171 265.033485 0)
			(layer "F.Fab")
			(hide yes)
			(effects
				(font
					(size 1 1)
					(thickness 0.15)
				)
			)
		)
		(property "License" "Apache-2.0"
			(at 73.039171 265.033485 0)
			(layer "F.Fab")
			(hide yes)
			(effects
				(font
					(size 1 1)
					(thickness 0.15)
				)
			)
		)
		(property "MPN" "XC7K70T-1FBG484C"
			(at 73.039171 265.033485 0)
			(layer "F.Fab")
			(hide yes)
			(effects
				(font
					(size 1 1)
					(thickness 0.15)
				)
			)
		)
		(property "Manufacturer" "AMD-Xilinx"
			(at 73.039171 265.033485 0)
			(layer "F.Fab")
			(hide yes)
			(effects
				(font
					(size 1 1)
					(thickness 0.15)
				)
			)
		)
		(sheetname "FPGA Banks")
		(sheetfile "fpga-banks.kicad_sch")
		(attr smd)
		(pad "J10" smd circle
			(at -1.5 -2.5 270)
			(size 0.51 0.51)
			(layers "F.Cu" "F.Mask" "F.Paste")
			(net 5 "GND")
			(pinfunction "GND")
			(pintype "passive")
		)
		(pad "J11" smd circle
			(at -0.5 -2.5 270)
			(size 0.51 0.51)
			(layers "F.Cu" "F.Mask" "F.Paste")
			(net 465 "1V0_SYS")
			(pinfunction "VCCINT")
			(pintype "power_in")
		)
		(pad "J12" smd circle
			(at 0.5 -2.5 270)
			(size 0.51 0.51)
			(layers "F.Cu" "F.Mask" "F.Paste")
			(net 5 "GND")
			(pinfunction "GND")
			(pintype "passive")
		)
		(pad "J13" smd circle
			(at 1.5 -2.5 270)
			(size 0.51 0.51)
			(layers "F.Cu" "F.Mask" "F.Paste")
			(net 465 "1V0_SYS")
			(pinfunction "VCCINT")
			(pintype "passive")
		)
		(pad "J14" smd circle
			(at 2.5 -2.5 270)
			(size 0.51 0.51)
			(layers "F.Cu" "F.Mask" "F.Paste")
			(net 5 "GND")
			(pinfunction "GND")
			(pintype "passive")
		)
		(pad "J15" smd circle
			(at 3.5 -2.5 270)
			(size 0.51 0.51)
			(layers "F.Cu" "F.Mask" "F.Paste")
			(net 465 "1V0_SYS")
			(pinfunction "VCCINT")
			(pintype "passive")
		)
		(pad "J16" smd circle
			(at 4.5 -2.5 270)
			(size 0.51 0.51)
			(layers "F.Cu" "F.Mask" "F.Paste")
			(net 389 "unconnected-(U3G-IO_L16P_T2_A28_15-PadJ16)")
			(pinfunction "IO_L16P_T2_A28_15")
			(pintype "bidirectional+no_connect")
		)
		(pad "J17" smd circle
			(at 5.5 -2.5 270)
			(size 0.51 0.51)
			(layers "F.Cu" "F.Mask" "F.Paste")
			(net 408 "unconnected-(U3G-IO_L16N_T2_A27_15-PadJ17)")
			(pinfunction "IO_L16N_T2_A27_15")
			(pintype "bidirectional+no_connect")
		)
		(pad "J18" smd circle
			(at 6.5 -2.5 270)
			(size 0.51 0.51)
			(layers "F.Cu" "F.Mask" "F.Paste")
			(net 5 "GND")
			(pinfunction "GND")
			(pintype "passive")
		)
		(pad "J19" smd circle
			(at 7.5 -2.5 270)
			(size 0.51 0.51)
			(layers "F.Cu" "F.Mask" "F.Paste")
			(net 217 "EMCCLK")
			(pinfunction "IO_L3N_T0_DQS_EMCCLK_14")
			(pintype "bidirectional")
		)
		(pad "J20" smd circle
			(at 8.5 -2.5 270)
			(size 0.51 0.51)
			(layers "F.Cu" "F.Mask" "F.Paste")
			(net 409 "unconnected-(U3H-IO_L11P_T1_SRCC_14-PadJ20)")
			(pinfunction "IO_L11P_T1_SRCC_14")
			(pintype "bidirectional+no_connect")
		)
		(pad "J21" smd circle
			(at 9.5 -2.5 270)
			(size 0.51 0.51)
			(layers "F.Cu" "F.Mask" "F.Paste")
			(net 50 "TMDS_D2_P")
			(pinfunction "IO_L10P_T1_D14_14")
			(pintype "bidirectional")
		)
		(pad "J22" smd circle
			(at 10.5 -2.5 270)
			(size 0.51 0.51)
			(layers "F.Cu" "F.Mask" "F.Paste")
			(net 51 "TMDS_D2_N")
			(pinfunction "IO_L10N_T1_D15_14")
			(pintype "bidirectional")
		)
		(pad "K1" smd circle
			(at -10.5 -1.5 270)
			(size 0.51 0.51)
			(layers "F.Cu" "F.Mask" "F.Paste")
			(net 349 "DQ02_A")
			(pinfunction "IO_L2P_T0_34")
			(pintype "bidirectional")
		)
		(pad "K2" smd circle
			(at -9.5 -1.5 270)
			(size 0.51 0.51)
			(layers "F.Cu" "F.Mask" "F.Paste")
			(net 350 "DQ01_A")
			(pinfunction "IO_L4N_T0_34")
			(pintype "bidirectional")
		)
		(pad "K3" smd circle
			(at -8.5 -1.5 270)
			(size 0.51 0.51)
			(layers "F.Cu" "F.Mask" "F.Paste")
			(net 348 "DQ03_A")
			(pinfunction "IO_L4P_T0_34")
			(pintype "bidirectional")
		)
		(pad "K4" smd circle
			(at -7.5 -1.5 270)
			(size 0.51 0.51)
			(layers "F.Cu" "F.Mask" "F.Paste")
			(net 511 "VRN")
			(pinfunction "IO_0_VRN_34")
			(pintype "bidirectional")
		)
		(pad "K5" smd circle
			(at -6.5 -1.5 270)
			(size 0.51 0.51)
			(layers "F.Cu" "F.Mask" "F.Paste")
			(net 5 "GND")
			(pinfunction "GND")
			(pintype "passive")
		)
		(pad "K6" smd circle
			(at -5.5 -1.5 270)
			(size 0.51 0.51)
			(layers "F.Cu" "F.Mask" "F.Paste")
			(net 10 "TDI_JTAG")
			(pinfunction "TDI_0")
			(pintype "bidirectional")
		)
		(pad "K7" smd circle
			(at -4.5 -1.5 270)
			(size 0.51 0.51)
			(layers "F.Cu" "F.Mask" "F.Paste")
			(net 8 "TCK_JTAG")
			(pinfunction "TCK_0")
			(pintype "bidirectional")
		)
		(pad "K8" smd circle
			(at -3.5 -1.5 270)
			(size 0.51 0.51)
			(layers "F.Cu" "F.Mask" "F.Paste")
			(net 465 "1V0_SYS")
			(pinfunction "VCCINT")
			(pintype "passive")
		)
		(pad "K9" smd circle
			(at -2.5 -1.5 270)
			(size 0.51 0.51)
			(layers "F.Cu" "F.Mask" "F.Paste")
			(net 5 "GND")
			(pinfunction "GND")
			(pintype "passive")
		)
		(pad "K10" smd circle
			(at -1.5 -1.5 270)
			(size 0.51 0.51)
			(layers "F.Cu" "F.Mask" "F.Paste")
			(net 460 "1V8_SYS")
			(pinfunction "VCCAUX")
			(pintype "power_in")
		)
		(pad "K11" smd circle
			(at -0.5 -1.5 270)
			(size 0.51 0.51)
			(layers "F.Cu" "F.Mask" "F.Paste")
			(net 5 "GND")
			(pinfunction "GNDADC_0")
			(pintype "power_in")
		)
		(pad "K12" smd circle
			(at 0.5 -1.5 270)
			(size 0.51 0.51)
			(layers "F.Cu" "F.Mask" "F.Paste")
			(net 460 "1V8_SYS")
			(pinfunction "VCCADC_0")
			(pintype "power_in")
		)
		(pad "K13" smd circle
			(at 1.5 -1.5 270)
			(size 0.51 0.51)
			(layers "F.Cu" "F.Mask" "F.Paste")
			(net 5 "GND")
			(pinfunction "GND")
			(pintype "passive")
		)
		(pad "K14" smd circle
			(at 2.5 -1.5 270)
			(size 0.51 0.51)
			(layers "F.Cu" "F.Mask" "F.Paste")
			(net 465 "1V0_SYS")
			(pinfunction "VCCINT")
			(pintype "passive")
		)
		(pad "K15" smd circle
			(at 3.5 -1.5 270)
			(size 0.51 0.51)
			(layers "F.Cu" "F.Mask" "F.Paste")
			(net 5 "GND")
			(pinfunction "GND")
			(pintype "passive")
		)
		(pad "K16" smd circle
			(at 4.5 -1.5 270)
			(size 0.51 0.51)
			(layers "F.Cu" "F.Mask" "F.Paste")
			(net 410 "unconnected-(U3H-IO_0_14-PadK16)")
			(pinfunction "IO_0_14")
			(pintype "bidirectional+no_connect")
		)
		(pad "K17" smd circle
			(at 5.5 -1.5 270)
			(size 0.51 0.51)
			(layers "F.Cu" "F.Mask" "F.Paste")
			(net 411 "unconnected-(U3H-IO_L6N_T0_D08_VREF_14-PadK17)")
			(pinfunction "IO_L6N_T0_D08_VREF_14")
			(pintype "bidirectional+no_connect")
		)
		(pad "K18" smd circle
			(at 6.5 -1.5 270)
			(size 0.51 0.51)
			(layers "F.Cu" "F.Mask" "F.Paste")
			(net 95 "PUDC_B")
			(pinfunction "IO_L3P_T0_DQS_PUDC_B_14")
			(pintype "bidirectional")
		)
		(pad "K19" smd circle
			(at 7.5 -1.5 270)
			(size 0.51 0.51)
			(layers "F.Cu" "F.Mask" "F.Paste")
			(net 412 "unconnected-(U3H-IO_L5N_T0_D07_14-PadK19)")
			(pinfunction "IO_L5N_T0_D07_14")
			(pintype "bidirectional+no_connect")
		)
		(pad "K20" smd circle
			(at 8.5 -1.5 270)
			(size 0.51 0.51)
			(layers "F.Cu" "F.Mask" "F.Paste")
			(net 459 "3V3_SYS")
			(pinfunction "VCCO_14")
			(pintype "passive")
		)
		(pad "K21" smd circle
			(at 9.5 -1.5 270)
			(size 0.51 0.51)
			(layers "F.Cu" "F.Mask" "F.Paste")
			(net 48 "TMDS_D1_P")
			(pinfunction "IO_L16P_T2_CSI_B_14")
			(pintype "bidirectional")
		)
		(pad "K22" smd circle
			(at 10.5 -1.5 270)
			(size 0.51 0.51)
			(layers "F.Cu" "F.Mask" "F.Paste")
			(net 49 "TMDS_D1_N")
			(pinfunction "IO_L16N_T2_A15_D31_14")
			(pintype "bidirectional")
		)
		(pad "L1" smd circle
			(at -10.5 -0.5 270)
			(size 0.51 0.51)
			(layers "F.Cu" "F.Mask" "F.Paste")
			(net 351 "DQ00_A")
			(pinfunction "IO_L2N_T0_34")
			(pintype "bidirectional")
		)
		(pad "L2" smd circle
			(at -9.5 -0.5 270)
			(size 0.51 0.51)
			(layers "F.Cu" "F.Mask" "F.Paste")
			(net 5 "GND")
			(pinfunction "GND")
			(pintype "passive")
		)
		(pad "L3" smd circle
			(at -8.5 -0.5 270)
			(size 0.51 0.51)
			(layers "F.Cu" "F.Mask" "F.Paste")
			(net 394 "CA_0A")
			(pinfunction "IO_L1P_T0_34")
			(pintype "bidirectional")
		)
		(pad "L4" smd circle
			(at -7.5 -0.5 270)
			(size 0.51 0.51)
			(layers "F.Cu" "F.Mask" "F.Paste")
			(net 510 "VREF_34")
			(pinfunction "IO_L6N_T0_VREF_34")
			(pintype "bidirectional")
		)
		(pad "L5" smd circle
			(at -6.5 -0.5 270)
			(size 0.51 0.51)
			(layers "F.Cu" "F.Mask" "F.Paste")
			(net 393 "CA_1A")
			(pinfunction "IO_L6P_T0_34")
			(pintype "bidirectional")
		)
		(pad "L6" smd circle
			(at -5.5 -0.5 270)
			(size 0.51 0.51)
			(layers "F.Cu" "F.Mask" "F.Paste")
			(net 9 "TMS_JTAG")
			(pinfunction "TMS_0")
			(pintype "bidirectional")
		)
		(pad "L7" smd circle
			(at -4.5 -0.5 270)
			(size 0.51 0.51)
			(layers "F.Cu" "F.Mask" "F.Paste")
			(net 210 "INIT_B")
			(pinfunction "INIT_B_0")
			(pintype "bidirectional")
		)
		(pad "L8" smd circle
			(at -3.5 -0.5 270)
			(size 0.51 0.51)
			(layers "F.Cu" "F.Mask" "F.Paste")
			(net 5 "GND")
			(pinfunction "GND")
			(pintype "passive")
		)
		(pad "L9" smd circle
			(at -2.5 -0.5 270)
			(size 0.51 0.51)
			(layers "F.Cu" "F.Mask" "F.Paste")
			(net 465 "1V0_SYS")
			(pinfunction "VCCINT")
			(pintype "passive")
		)
		(pad "L10" smd circle
			(at -1.5 -0.5 270)
			(size 0.51 0.51)
			(layers "F.Cu" "F.Mask" "F.Paste")
			(net 5 "GND")
			(pinfunction "GND")
			(pintype "passive")
		)
		(pad "L11" smd circle
			(at -0.5 -0.5 270)
			(size 0.51 0.51)
			(layers "F.Cu" "F.Mask" "F.Paste")
			(net 5 "GND")
			(pinfunction "VREFN_0")
			(pintype "bidirectional")
		)
		(pad "L12" smd circle
			(at 0.5 -0.5 270)
			(size 0.51 0.51)
			(layers "F.Cu" "F.Mask" "F.Paste")
			(net 5 "GND")
			(pinfunction "VP_0")
			(pintype "bidirectional")
		)
		(pad "L13" smd circle
			(at 1.5 -0.5 270)
			(size 0.51 0.51)
			(layers "F.Cu" "F.Mask" "F.Paste")
			(net 465 "1V0_SYS")
			(pinfunction "VCCBRAM")
			(pintype "power_in")
		)
		(pad "L14" smd circle
			(at 2.5 -0.5 270)
			(size 0.51 0.51)
			(layers "F.Cu" "F.Mask" "F.Paste")
			(net 5 "GND")
			(pinfunction "GND")
			(pintype "passive")
		)
		(pad "L15" smd circle
			(at 3.5 -0.5 270)
			(size 0.51 0.51)
			(layers "F.Cu" "F.Mask" "F.Paste")
			(net 465 "1V0_SYS")
			(pinfunction "VCCINT")
			(pintype "passive")
		)
		(pad "L16" smd circle
			(at 4.5 -0.5 270)
			(size 0.51 0.51)
			(layers "F.Cu" "F.Mask" "F.Paste")
			(net 212 "FCS_B")
			(pinfunction "IO_L6P_T0_FCS_B_14")
			(pintype "bidirectional")
		)
		(pad "L17" smd circle
			(at 5.5 -0.5 270)
			(size 0.51 0.51)
			(layers "F.Cu" "F.Mask" "F.Paste")
			(net 459 "3V3_SYS")
			(pinfunction "VCCO_14")
			(pintype "passive")
		)
		(pad "L18" smd circle
			(at 6.5 -0.5 270)
			(size 0.51 0.51)
			(layers "F.Cu" "F.Mask" "F.Paste")
			(net 413 "unconnected-(U3H-IO_L5P_T0_D06_14-PadL18)")
			(pinfunction "IO_L5P_T0_D06_14")
			(pintype "bidirectional+no_connect")
		)
		(pad "L19" smd circle
			(at 7.5 -0.5 270)
			(size 0.51 0.51)
			(layers "F.Cu" "F.Mask" "F.Paste")
			(net 38 "GCLK100")
			(pinfunction "IO_L12P_T1_MRCC_14")
			(pintype "bidirectional")
		)
		(pad "L20" smd circle
			(at 8.5 -0.5 270)
			(size 0.51 0.51)
			(layers "F.Cu" "F.Mask" "F.Paste")
			(net 414 "unconnected-(U3H-IO_L12N_T1_MRCC_14-PadL20)")
			(pinfunction "IO_L12N_T1_MRCC_14")
			(pintype "bidirectional+no_connect")
		)
		(pad "L21" smd circle
			(at 9.5 -0.5 270)
			(size 0.51 0.51)
			(layers "F.Cu" "F.Mask" "F.Paste")
			(net 415 "unconnected-(U3H-IO_L18N_T2_A11_D27_14-PadL21)")
			(pinfunction "IO_L18N_T2_A11_D27_14")
			(pintype "bidirectional+no_connect")
		)
		(pad "L22" smd circle
			(at 10.5 -0.5 270)
			(size 0.51 0.51)
			(layers "F.Cu" "F.Mask" "F.Paste")
			(net 5 "GND")
			(pinfunction "GND")
			(pintype "passive")
		)
		(pad "M1" smd circle
			(at -10.5 0.5 270)
			(size 0.51 0.51)
			(layers "F.Cu" "F.Mask" "F.Paste")
			(net 650 "DQ_S0_N")
			(pinfunction "IO_L3N_T0_DQS_34")
			(pintype "bidirectional")
		)
		(pad "M2" smd circle
			(at -9.5 0.5 270)
			(size 0.51 0.51)
			(layers "F.Cu" "F.Mask" "F.Paste")
			(net 651 "DQ_S0_P")
			(pinfunction "IO_L3P_T0_DQS_34")
			(pintype "bidirectional")
		)
		(pad "M3" smd circle
			(at -8.5 0.5 270)
			(size 0.51 0.51)
			(layers "F.Cu" "F.Mask" "F.Paste")
			(net 347 "DMI_0A")
			(pinfunction "IO_L1N_T0_34")
			(pintype "bidirectional")
		)
		(pad "M4" smd circle
			(at -7.5 0.5 270)
			(size 0.51 0.51)
			(layers "F.Cu" "F.Mask" "F.Paste")
			(net 66 "VDDQ")
			(pinfunction "VCCO_34")
			(pintype "passive")
		)
		(pad "M5" smd circle
			(at -6.5 0.5 270)
			(size 0.51 0.51)
			(layers "F.Cu" "F.Mask" "F.Paste")
			(net 397 "IO_M5")
			(pinfunction "IO_L9P_T1_DQS_34")
			(pintype "bidirectional")
		)
		(pad "M6" smd circle
			(at -5.5 0.5 270)
			(size 0.51 0.51)
			(layers "F.Cu" "F.Mask" "F.Paste")
			(net 208 "PROGRAM_B")
			(pinfunction "PROGRAM_B_0")
			(pintype "bidirectional")
		)
		(pad "M7" smd circle
			(at -4.5 0.5 270)
			(size 0.51 0.51)
			(layers "F.Cu" "F.Mask" "F.Paste")
			(net 219 "CFGBVS")
			(pinfunction "CFGBVS_0")
			(pintype "bidirectional")
		)
		(pad "M8" smd circle
			(at -3.5 0.5 270)
			(size 0.51 0.51)
			(layers "F.Cu" "F.Mask" "F.Paste")
			(net 465 "1V0_SYS")
			(pinfunction "VCCINT")
			(pintype "passive")
		)
		(pad "M9" smd circle
			(at -2.5 0.5 270)
			(size 0.51 0.51)
			(layers "F.Cu" "F.Mask" "F.Paste")
			(net 5 "GND")
			(pinfunction "GND")
			(pintype "passive")
		)
		(pad "M10" smd circle
			(at -1.5 0.5 270)
			(size 0.51 0.51)
			(layers "F.Cu" "F.Mask" "F.Paste")
			(net 460 "1V8_SYS")
			(pinfunction "VCCAUX")
			(pintype "passive")
		)
		(pad "M11" smd circle
			(at -0.5 0.5 270)
			(size 0.51 0.51)
			(layers "F.Cu" "F.Mask" "F.Paste")
			(net 5 "GND")
			(pinfunction "VN_0")
			(pintype "bidirectional")
		)
		(pad "M12" smd circle
			(at 0.5 0.5 270)
			(size 0.51 0.51)
			(layers "F.Cu" "F.Mask" "F.Paste")
			(net 5 "GND")
			(pinfunction "VREFP_0")
			(pintype "bidirectional")
		)
		(pad "M13" smd circle
			(at 1.5 0.5 270)
			(size 0.51 0.51)
			(layers "F.Cu" "F.Mask" "F.Paste")
			(net 5 "GND")
			(pinfunction "GND")
			(pintype "passive")
		)
		(pad "M14" smd circle
			(at 2.5 0.5 270)
			(size 0.51 0.51)
			(layers "F.Cu" "F.Mask" "F.Paste")
			(net 465 "1V0_SYS")
			(pinfunction "VCCINT")
			(pintype "passive")
		)
		(pad "M15" smd circle
			(at 3.5 0.5 270)
			(size 0.51 0.51)
			(layers "F.Cu" "F.Mask" "F.Paste")
			(net 5 "GND")
			(pinfunction "GND")
			(pintype "passive")
		)
		(pad "M16" smd circle
			(at 4.5 0.5 270)
			(size 0.51 0.51)
			(layers "F.Cu" "F.Mask" "F.Paste")
			(net 416 "unconnected-(U3H-IO_25_14-PadM16)")
			(pinfunction "IO_25_14")
			(pintype "bidirectional+no_connect")
		)
		(pad "M17" smd circle
			(at 5.5 0.5 270)
			(size 0.51 0.51)
			(layers "F.Cu" "F.Mask" "F.Paste")
			(net 417 "unconnected-(U3H-IO_L14P_T2_SRCC_14-PadM17)")
			(pinfunction "IO_L14P_T2_SRCC_14")
			(pintype "bidirectional+no_connect")
		)
		(pad "M18" smd circle
			(at 6.5 0.5 270)
			(size 0.51 0.51)
			(layers "F.Cu" "F.Mask" "F.Paste")
			(net 418 "unconnected-(U3H-IO_L14N_T2_SRCC_14-PadM18)")
			(pinfunction "IO_L14N_T2_SRCC_14")
			(pintype "bidirectional+no_connect")
		)
		(pad "M19" smd circle
			(at 7.5 0.5 270)
			(size 0.51 0.51)
			(layers "F.Cu" "F.Mask" "F.Paste")
			(net 5 "GND")
			(pinfunction "GND")
			(pintype "passive")
		)
		(pad "M20" smd circle
			(at 8.5 0.5 270)
			(size 0.51 0.51)
			(layers "F.Cu" "F.Mask" "F.Paste")
			(net 419 "unconnected-(U3H-IO_L18P_T2_A12_D28_14-PadM20)")
			(pinfunction "IO_L18P_T2_A12_D28_14")
			(pintype "bidirectional+no_connect")
		)
		(pad "M21" smd circle
			(at 9.5 0.5 270)
			(size 0.51 0.51)
			(layers "F.Cu" "F.Mask" "F.Paste")
			(net 420 "unconnected-(U3H-IO_L17N_T2_A13_D29_14-PadM21)")
			(pinfunction "IO_L17N_T2_A13_D29_14")
			(pintype "bidirectional+no_connect")
		)
		(pad "M22" smd circle
			(at 10.5 0.5 270)
			(size 0.51 0.51)
			(layers "F.Cu" "F.Mask" "F.Paste")
			(net 421 "unconnected-(U3H-IO_L15N_T2_DQS_DOUT_CSO_B_14-PadM22)")
			(pinfunction "IO_L15N_T2_DQS_DOUT_CSO_B_14")
			(pintype "bidirectional+no_connect")
		)
		(pad "N1" smd circle
			(at -10.5 1.5 270)
			(size 0.51 0.51)
			(layers "F.Cu" "F.Mask" "F.Paste")
			(net 66 "VDDQ")
			(pinfunction "VCCO_34")
			(pintype "passive")
		)
		(pad "N2" smd circle
			(at -9.5 1.5 270)
			(size 0.51 0.51)
			(layers "F.Cu" "F.Mask" "F.Paste")
			(net 346 "DQ07_A")
			(pinfunction "IO_L5N_T0_34")
			(pintype "bidirectional")
		)
		(pad "N3" smd circle
			(at -8.5 1.5 270)
			(size 0.51 0.51)
			(layers "F.Cu" "F.Mask" "F.Paste")
			(net 395 "CS0_A")
			(pinfunction "IO_L5P_T0_34")
			(pintype "bidirectional")
		)
	)
)
